# S9S_MB_2U (Grand Teton) — schematic netlist excerpt (pin names and nets, part order shuffled) for the footprints in the layout excerpt that follows; sources: Cadence DE-HDL packaged netlist, KiCad conversion of 03242023_DA0F0TMBIJ0_F0T_Motherboard_J_brd_V01_OCP.brd

J28  SCONN288_ADR50017P087CC  SCONN288_ADR50017-P087CC IO  pkg DDR288S_1-1VXB  page 109
  VIN_BULK0  = P12V_S3_AUX_CPU1_NVDIMM
  RFU0  = TP_CHF_CPU1_DIMM2_FRU_0
  VIN_MGMT  = P3V3_AUX
  HSCL  = I3C_SPD_DDREFGH_CPU1_LVC1_SCL_3
  HSDA  = I3C_SPD_DDREFGH_CPU1_LVC1_SDA
  VSS0  = GND
  DQ0_A  = M_F_CPU1_SA_DQ<0>
  VSS1  = GND
  DQ1_A  = M_F_CPU1_SA_DQ<1>
  VSS2  = GND
  DQS0_A_T  = M_F_CPU1_SA_DQS_DP<0>
  DQS0_A_C  = M_F_CPU1_SA_DQS_DN<0>
  VSS3  = GND
  DQ4_A  = M_F_CPU1_SA_DQ<4>
  VSS4  = GND
  DQ5_A  = M_F_CPU1_SA_DQ<5>
  VSS5  = GND
  DQ8_A  = M_F_CPU1_SA_DQ<8>
  VSS6  = GND
  DQ9_A  = M_F_CPU1_SA_DQ<9>
  VSS7  = GND
  DQS1_A_T  = M_F_CPU1_SA_DQS_DP<1>
  DQS1_A_C  = M_F_CPU1_SA_DQS_DN<1>
  VSS8  = GND
  DQ12_A  = M_F_CPU1_SA_DQ<12>
  VSS9  = GND
  DQ13_A  = M_F_CPU1_SA_DQ<13>
  VSS10  = GND
  DQ16_A  = M_F_CPU1_SA_DQ<16>
  VSS11  = GND
  DQ17_A  = M_F_CPU1_SA_DQ<17>
  VSS12  = GND
  DQS2_A_T  = M_F_CPU1_SA_DQS_DP<2>
  DQS2_A_C  = M_F_CPU1_SA_DQS_DN<2>
  VSS13  = GND
  DQ20_A  = M_F_CPU1_SA_DQ<20>
  VSS14  = GND
  DQ21_A  = M_F_CPU1_SA_DQ<21>
  VSS15  = GND
  DQ24_A  = M_F_CPU1_SA_DQ<24>
  VSS16  = GND
  DQ25_A  = M_F_CPU1_SA_DQ<25>
  VSS17  = GND
  DQS3_A_T  = M_F_CPU1_SA_DQS_DP<3>
  DQS3_A_C  = M_F_CPU1_SA_DQS_DN<3>
  VSS18  = GND
  DQ28_A  = M_F_CPU1_SA_DQ<28>
  VSS19  = GND
  DQ29_A  = M_F_CPU1_SA_DQ<29>
  VSS20  = GND
  CB0_A  = M_F_CPU1_SA_CB<0>
  VSS21  = GND
  CB1_A  = M_F_CPU1_SA_CB<1>
  VSS22  = GND
  DQS4_A_T  = M_F_CPU1_SA_DQS_DP<4>
  DQS4_A_C  = M_F_CPU1_SA_DQS_DN<4>
  VSS23  = GND
  CB4_A  = M_F_CPU1_SA_CB<4>
  VSS24  = GND
  CB5_A  = M_F_CPU1_SA_CB<5>
  VSS25  = GND
  ALERT_N  = M_F_CPU1_ALERT_N
  VSS26  = GND
  CS0_A_N  = M_F_CPU1_SA_CS_N<2>
  VSS27  = GND
  CA0_A  = M_F_CPU1_SA_CA<0>
  VSS28  = GND
  CA2_A  = M_F_CPU1_SA_CA<2>
  VSS29  = GND
  CA4_A  = M_F_CPU1_SA_CA<4>
  VSS30  = GND
  CA6_A  = M_F_CPU1_SA_CA<6>
  VSS31  = GND
  PAR_A  = M_F_CPU1_SA_PAR
  VSS32  = GND
  CA0_B  = M_F_CPU1_SB_CA<0>
  VSS33  = GND
  CA2_B  = M_F_CPU1_SB_CA<2>
  VSS34  = GND
  CA4_B  = M_F_CPU1_SB_CA<4>
  VSS35  = GND
  CA6_B  = M_F_CPU1_SB_CA<6>
  VSS36  = GND
  CS0_B_N  = M_F_CPU1_SB_CS_N<2>
  VSS37  = GND
  \lbd||rsp_a_n\  = M_F_CPU1_SA_RSP<1>
  \lbs||rsp_b_n\  = M_F_CPU1_SB_RSP<1>
  VSS38  = GND
  CB4_B  = M_F_CPU1_SB_CB<4>
  VSS39  = GND
  CB5_B  = M_F_CPU1_SB_CB<5>
  VSS40  = GND
  \dqs9_b_t||tdqs9_b_t||dbi4_b_n\  = M_F_CPU1_SB_DQS_DP<9>
  \dqs9_b_c||tdqs9_b_c\  = M_F_CPU1_SB_DQS_DN<9>
  VSS41  = GND
  CB0_B  = M_F_CPU1_SB_CB<0>
  VSS42  = GND
  CB1_B  = M_F_CPU1_SB_CB<1>
  VSS43  = GND
  DQ0_B  = M_F_CPU1_SB_DQ<0>
  VSS44  = GND
  DQ1_B  = M_F_CPU1_SB_DQ<1>
  VSS45  = GND
  DQS0_B_T  = M_F_CPU1_SB_DQS_DP<0>
  DQS0_B_C  = M_F_CPU1_SB_DQS_DN<0>
  VSS46  = GND
  DQ4_B  = M_F_CPU1_SB_DQ<4>
  VSS47  = GND
  DQ5_B  = M_F_CPU1_SB_DQ<5>
  VSS48  = GND
  DQ8_B  = M_F_CPU1_SB_DQ<8>
  VSS49  = GND
  DQ9_B  = M_F_CPU1_SB_DQ<9>
  VSS50  = GND
  DQS1_B_T  = M_F_CPU1_SB_DQS_DP<1>
  DQS1_B_C  = M_F_CPU1_SB_DQS_DN<1>
  VSS51  = GND
  DQ12_B  = M_F_CPU1_SB_DQ<12>
  VSS52  = GND
  DQ13_B  = M_F_CPU1_SB_DQ<13>
  VSS53  = GND
  DQ16_B  = M_F_CPU1_SB_DQ<16>
  VSS54  = GND
  DQ17_B  = M_F_CPU1_SB_DQ<17>
  VSS55  = GND
  DQS2_B_T  = M_F_CPU1_SB_DQS_DP<2>
  DQS2_B_C  = M_F_CPU1_SB_DQS_DN<2>
  VSS56  = GND
  DQ20_B  = M_F_CPU1_SB_DQ<20>
  VSS57  = GND
  DQ21_B  = M_F_CPU1_SB_DQ<21>
  VSS58  = GND
  DQ24_B  = M_F_CPU1_SB_DQ<24>
  VSS59  = GND
  DQ25_B  = M_F_CPU1_SB_DQ<25>
  VSS60  = GND
  DQS3_B_T  = M_F_CPU1_SB_DQS_DP<3>
  DQS3_B_C  = M_F_CPU1_SB_DQS_DN<3>
  VSS61  = GND
  DQ28_B  = M_F_CPU1_SB_DQ<28>
  VSS62  = GND
  DQ29_B  = M_F_CPU1_SB_DQ<29>
  VSS63  = GND
  RFU1  = TP_CHF_CPU1_DIMM2_FRU_1
  VIN_BULK1  = P12V_S3_AUX_CPU1_NVDIMM
  VIN_BULK2  = P12V_S3_AUX_CPU1_NVDIMM
  \pwr_good||fail_n\  = PWRGD_CHF_CPU1_DIMM2
  HSA  = PD_CHF_CPU1_DIMM2_SAA
  RFU2  = TP_CHF_CPU1_DIMM2_FRU_2
  RFU3  = TP_CHF_CPU1_DIMM2_FRU_3
  VSS64  = GND
  DQ2_A  = M_F_CPU1_SA_DQ<2>
  VSS65  = GND
  DQ3_A  = M_F_CPU1_SA_DQ<3>
  VSS66  = GND
  \dqs5_a_c||tdqs5_a_c||dqs5_a_t||tdqs5_a_t\  = M_F_CPU1_SA_DQS_DN<5>
  \dqs5_a_t||tdqs5_a_t\  = M_F_CPU1_SA_DQS_DP<5>
  VSS67  = GND
  DQ6_A  = M_F_CPU1_SA_DQ<6>
  VSS68  = GND
  DQ7_A  = M_F_CPU1_SA_DQ<7>
  VSS69  = GND
  DQ10_A  = M_F_CPU1_SA_DQ<10>
  VSS70  = GND
  DQ11_A  = M_F_CPU1_SA_DQ<11>
  VSS71  = GND
  \dqs6_a_c||tdqs6_a_c||dqs6_a_t||tdqs6_a_t\  = M_F_CPU1_SA_DQS_DN<6>
  \dqs6_a_t||tdqs6_a_t\  = M_F_CPU1_SA_DQS_DP<6>
  VSS72  = GND
  DQ14_A  = M_F_CPU1_SA_DQ<14>
  VSS73  = GND
  DQ15_A  = M_F_CPU1_SA_DQ<15>
  VSS74  = GND
  DQ18_A  = M_F_CPU1_SA_DQ<18>
  VSS75  = GND
  DQ19_A  = M_F_CPU1_SA_DQ<19>
  VSS76  = GND
  \dqs7_a_c||tdqs7_a_c\  = M_F_CPU1_SA_DQS_DN<7>
  \dqs7_a_t||tdqs7_a_t\  = M_F_CPU1_SA_DQS_DP<7>
  VSS77  = GND
  DQ22_A  = M_F_CPU1_SA_DQ<22>
  VSS78  = GND
  DQ23_A  = M_F_CPU1_SA_DQ<23>
  VSS79  = GND
  DQ26_A  = M_F_CPU1_SA_DQ<26>
  VSS80  = GND
  DQ27_A  = M_F_CPU1_SA_DQ<27>
  VSS81  = GND
  \dqs8_a_c||tdqs8_a_c\  = M_F_CPU1_SA_DQS_DN<8>
  \dqs8_a_t||tdqs8_a_t\  = M_F_CPU1_SA_DQS_DP<8>
  VSS82  = GND
  DQ30_A  = M_F_CPU1_SA_DQ<30>
  VSS83  = GND
  DQ31_A  = M_F_CPU1_SA_DQ<31>
  VSS84  = GND
  CB2_A  = M_F_CPU1_SA_CB<2>
  VSS85  = GND
  CB3_A  = M_F_CPU1_SA_CB<3>
  VSS86  = GND
  \dqs9_a_c||tdqs9_a_c\  = M_F_CPU1_SA_DQS_DN<9>
  \dqs9_a_t||tdqs9_a_t\  = M_F_CPU1_SA_DQS_DP<9>
  VSS87  = GND
  CB6_A  = M_F_CPU1_SA_CB<6>
  VSS88  = GND
  CB7_A  = M_F_CPU1_SA_CB<7>
  VSS89  = GND
  RESET_N  = RST_M_EF_CPU1_FPGA_N
  VSS90  = GND
  CS1_A_N  = M_F_CPU1_SA_CS_N<3>
  VSS91  = GND
  CA1_A  = M_F_CPU1_SA_CA<1>
  VSS92  = GND
  CA3_A  = M_F_CPU1_SA_CA<3>
  VSS93  = GND
  CA5_A  = M_F_CPU1_SA_CA<5>
  VSS94  = GND
  CK_T  = M_F_CPU1_CLK_DP<1>
  CK_C  = M_F_CPU1_CLK_DN<1>
  VSS95  = GND
  RFU4  = TP_CHF_CPU1_DIMM2_FRU_4
  CA1_B  = M_F_CPU1_SB_CA<1>
  VSS96  = GND
  CA3_B  = M_F_CPU1_SB_CA<3>
  VSS97  = GND
  CA5_B  = M_F_CPU1_SB_CA<5>
  VSS98  = GND
  PAR_B  = M_F_CPU1_SB_PAR
  VSS99  = GND
  CS1_B_N  = M_F_CPU1_SB_CS_N<3>
  VSS100  = GND
  RFU5  = TP_CHF_CPU1_DIMM2_FRU_5
  RFU6  = TP_CHF_CPU1_DIMM2_FRU_6
  VSS101  = GND
  CB6_B  = M_F_CPU1_SB_CB<6>
  VSS102  = GND
  CB7_B  = M_F_CPU1_SB_CB<7>
  VSS103  = GND
  DQS4_B_C  = M_F_CPU1_SB_DQS_DN<4>
  DQS4_B_T  = M_F_CPU1_SB_DQS_DP<4>
  VSS104  = GND
  CB2_B  = M_F_CPU1_SB_CB<2>
  VSS105  = GND
  CB3_B  = M_F_CPU1_SB_CB<3>
  VSS106  = GND
  DQ2_B  = M_F_CPU1_SB_DQ<2>
  VSS107  = GND
  DQ3_B  = M_F_CPU1_SB_DQ<3>
  VSS108  = GND
  \dqs5_b_c||tdqs5_b_c\  = M_F_CPU1_SB_DQS_DN<5>
  \dqs5_b_t||tdqs5_b_t\  = M_F_CPU1_SB_DQS_DP<5>
  VSS109  = GND
  DQ6_B  = M_F_CPU1_SB_DQ<6>
  VSS110  = GND
  DQ7_B  = M_F_CPU1_SB_DQ<7>
  VSS111  = GND
  DQ10_B  = M_F_CPU1_SB_DQ<10>
  VSS112  = GND
  DQ11_B  = M_F_CPU1_SB_DQ<11>
  VSS113  = GND
  \dqs6_b_c||tdqs6_b_c\  = M_F_CPU1_SB_DQS_DN<6>
  \dqs6_b_t||tdqs6_b_t\  = M_F_CPU1_SB_DQS_DP<6>
  VSS114  = GND
  DQ14_B  = M_F_CPU1_SB_DQ<14>
  VSS115  = GND
  DQ15_B  = M_F_CPU1_SB_DQ<15>
  VSS116  = GND
  DQ18_B  = M_F_CPU1_SB_DQ<18>
  VSS117  = GND
  DQ19_B  = M_F_CPU1_SB_DQ<19>
  VSS118  = GND
  \dqs7_b_c||tdqs7_b_c\  = M_F_CPU1_SB_DQS_DN<7>
  \dqs7_b_t||tdqs7_b_t\  = M_F_CPU1_SB_DQS_DP<7>
  VSS119  = GND
  DQ22_B  = M_F_CPU1_SB_DQ<22>
  VSS120  = GND
  DQ23_B  = M_F_CPU1_SB_DQ<23>
  VSS121  = GND
  DQ26_B  = M_F_CPU1_SB_DQ<26>
  VSS122  = GND
  DQ27_B  = M_F_CPU1_SB_DQ<27>
  VSS123  = GND
  \dqs8_b_c||tdqs8_b_c\  = M_F_CPU1_SB_DQS_DN<8>
  \dqs8_b_t||tdqs8_b_t\  = M_F_CPU1_SB_DQS_DP<8>
  VSS124  = GND
  DQ30_B  = M_F_CPU1_SB_DQ<30>
  VSS125  = GND
  DQ31_B  = M_F_CPU1_SB_DQ<31>
  VSS126  = GND
  G1  = GND
  G2  = GND
  G3  = GND

(kicad_pcb
	(version 20260206)
	(generator "pcbnew")
	(generator_version "10.0")
	(general
		(thickness 1.6)
		(legacy_teardrops no)
	)
	(paper "A4")
	(title_block
		(title "03242023_DA0F0TMBIJ0_F0T_Motherboard_J_brd_V01_OCP.brd")
		(comment 1 "Grand Teton / footprint 3431 of 6105 (J28), pads 46-91 of 291")
	)
	(layers
		(0 "F.Cu" signal "TOP")
		(4 "In1.Cu" signal "GND")
		(6 "In2.Cu" signal "IN1")
		(8 "In3.Cu" signal "GND1")
		(10 "In4.Cu" signal "IN2")
		(12 "In5.Cu" signal "GND2")
		(14 "In6.Cu" signal "IN3")
		(16 "In7.Cu" signal "GND3")
		(18 "In8.Cu" signal "VCC")
		(20 "In9.Cu" signal "VCC1")
		(22 "In10.Cu" signal "GND4")
		(24 "In11.Cu" signal "IN4")
		(26 "In12.Cu" signal "GND5")
		(28 "In13.Cu" signal "IN5")
		(30 "In14.Cu" signal "GND6")
		(32 "In15.Cu" signal "IN6")
		(34 "In16.Cu" signal "GND7")
		(2 "B.Cu" signal "BOTTOM")
		(9 "F.Adhes" user "F.Adhesive")
		(11 "B.Adhes" user "B.Adhesive")
		(13 "F.Paste" user "Package Geometry/Pastemask Top")
		(15 "B.Paste" user "Package Geometry/Pastemask Bottom")
		(5 "F.SilkS" user "Ref Des/Silkscreen Top")
		(7 "B.SilkS" user "Ref Des/Silkscreen Bottom")
		(1 "F.Mask" user "Board Geometry/Soldermask Top")
		(3 "B.Mask" user "Board Geometry/Soldermask Bottom")
		(17 "Dwgs.User" user "User.Drawings")
		(19 "Cmts.User" user "User.Comments")
		(21 "Eco1.User" user "User.Eco1")
		(23 "Eco2.User" user "User.Eco2")
		(25 "Edge.Cuts" user "Board Geometry/Outline")
		(27 "Margin" user)
		(31 "F.CrtYd" user "Package Geometry/Place Bound Top")
		(29 "B.CrtYd" user "Package Geometry/Place Bound Bottom")
		(35 "F.Fab" user "Ref Des/Assembly Top")
		(33 "B.Fab" user "Ref Des/Assembly Bottom")
	)
	(footprint ""
		(layer "F.Cu")
		(at 175.95088 -258.091686)
		(property "Reference" "J28"
			(at -0.26924 -81.680812 0)
			(unlocked yes)
			(layer "F.SilkS")
			(effects
				(font
					(size 0.7874 0.5842)
					(thickness 0.1524)
				)
				(justify left)
			)
		)
		(property "Value" ""
			(at 0 0 0)
			(layer "F.Fab")
			(effects
				(font
					(size 1.27 1.27)
				)
			)
		)
		(duplicate_pad_numbers_are_jumpers no)
		(pad "46" smd rect
			(at -2.050034 -25.07488 270)
			(size 0.519938 1.4986)
			(layers "F.Cu" "F.Mask" "F.Paste")
			(net "GND")
		)
		(pad "47" smd rect
			(at -2.050034 -24.224996 270)
			(size 0.519938 1.4986)
			(layers "F.Cu" "F.Mask" "F.Paste")
			(net "M_F_CPU1_SA_DQ<28>")
		)
		(pad "48" smd rect
			(at -2.050034 -23.375112 270)
			(size 0.519938 1.4986)
			(layers "F.Cu" "F.Mask" "F.Paste")
			(net "GND")
		)
		(pad "49" smd rect
			(at -2.050034 -22.524974 270)
			(size 0.519938 1.4986)
			(layers "F.Cu" "F.Mask" "F.Paste")
			(net "M_F_CPU1_SA_DQ<29>")
		)
		(pad "50" smd rect
			(at -2.050034 -21.67509 270)
			(size 0.519938 1.4986)
			(layers "F.Cu" "F.Mask" "F.Paste")
			(net "GND")
		)
		(pad "51" smd rect
			(at -2.050034 -20.824952 270)
			(size 0.519938 1.4986)
			(layers "F.Cu" "F.Mask" "F.Paste")
			(net "M_F_CPU1_SA_CB<0>")
		)
		(pad "52" smd rect
			(at -2.050034 -19.975068 270)
			(size 0.519938 1.4986)
			(layers "F.Cu" "F.Mask" "F.Paste")
			(net "GND")
		)
		(pad "53" smd rect
			(at -2.050034 -19.12493 270)
			(size 0.519938 1.4986)
			(layers "F.Cu" "F.Mask" "F.Paste")
			(net "M_F_CPU1_SA_CB<1>")
		)
		(pad "54" smd rect
			(at -2.050034 -18.275046 270)
			(size 0.519938 1.4986)
			(layers "F.Cu" "F.Mask" "F.Paste")
			(net "GND")
		)
		(pad "55" smd rect
			(at -2.050034 -17.424908 270)
			(size 0.519938 1.4986)
			(layers "F.Cu" "F.Mask" "F.Paste")
			(net "M_F_CPU1_SA_DQS_DP<4>")
		)
		(pad "56" smd rect
			(at -2.050034 -16.575024 270)
			(size 0.519938 1.4986)
			(layers "F.Cu" "F.Mask" "F.Paste")
			(net "M_F_CPU1_SA_DQS_DN<4>")
		)
		(pad "57" smd rect
			(at -2.050034 -15.724886 270)
			(size 0.519938 1.4986)
			(layers "F.Cu" "F.Mask" "F.Paste")
			(net "GND")
		)
		(pad "58" smd rect
			(at -2.050034 -14.875002 270)
			(size 0.519938 1.4986)
			(layers "F.Cu" "F.Mask" "F.Paste")
			(net "M_F_CPU1_SA_CB<4>")
		)
		(pad "59" smd rect
			(at -2.050034 -14.025118 270)
			(size 0.519938 1.4986)
			(layers "F.Cu" "F.Mask" "F.Paste")
			(net "GND")
		)
		(pad "60" smd rect
			(at -2.050034 -13.17498 270)
			(size 0.519938 1.4986)
			(layers "F.Cu" "F.Mask" "F.Paste")
			(net "M_F_CPU1_SA_CB<5>")
		)
		(pad "61" smd rect
			(at -2.050034 -12.325096 270)
			(size 0.519938 1.4986)
			(layers "F.Cu" "F.Mask" "F.Paste")
			(net "GND")
		)
		(pad "62" smd rect
			(at -2.050034 -11.474958 270)
			(size 0.519938 1.4986)
			(layers "F.Cu" "F.Mask" "F.Paste")
			(net "M_F_CPU1_ALERT_N")
		)
		(pad "63" smd rect
			(at -2.050034 -10.625074 270)
			(size 0.519938 1.4986)
			(layers "F.Cu" "F.Mask" "F.Paste")
			(net "GND")
		)
		(pad "64" smd rect
			(at -2.050034 -9.774936 270)
			(size 0.519938 1.4986)
			(layers "F.Cu" "F.Mask" "F.Paste")
			(net "M_F_CPU1_SA_CS_N<2>")
		)
		(pad "65" smd rect
			(at -2.050034 -8.925052 270)
			(size 0.519938 1.4986)
			(layers "F.Cu" "F.Mask" "F.Paste")
			(net "GND")
		)
		(pad "66" smd rect
			(at -2.050034 -8.074914 270)
			(size 0.519938 1.4986)
			(layers "F.Cu" "F.Mask" "F.Paste")
			(net "M_F_CPU1_SA_CA<0>")
		)
		(pad "67" smd rect
			(at -2.050034 -7.22503 270)
			(size 0.519938 1.4986)
			(layers "F.Cu" "F.Mask" "F.Paste")
			(net "GND")
		)
		(pad "68" smd rect
			(at -2.050034 -6.374892 270)
			(size 0.519938 1.4986)
			(layers "F.Cu" "F.Mask" "F.Paste")
			(net "M_F_CPU1_SA_CA<2>")
		)
		(pad "69" smd rect
			(at -2.050034 -5.525008 270)
			(size 0.519938 1.4986)
			(layers "F.Cu" "F.Mask" "F.Paste")
			(net "GND")
		)
		(pad "70" smd rect
			(at -2.050034 -4.675124 270)
			(size 0.519938 1.4986)
			(layers "F.Cu" "F.Mask" "F.Paste")
			(net "M_F_CPU1_SA_CA<4>")
		)
		(pad "71" smd rect
			(at -2.050034 -3.824986 270)
			(size 0.519938 1.4986)
			(layers "F.Cu" "F.Mask" "F.Paste")
			(net "GND")
		)
		(pad "72" smd rect
			(at -2.050034 -2.975102 270)
			(size 0.519938 1.4986)
			(layers "F.Cu" "F.Mask" "F.Paste")
			(net "M_F_CPU1_SA_CA<6>")
		)
		(pad "73" smd rect
			(at -2.050034 -2.124964 270)
			(size 0.519938 1.4986)
			(layers "F.Cu" "F.Mask" "F.Paste")
			(net "GND")
		)
		(pad "74" smd rect
			(at -2.050034 -1.27508 270)
			(size 0.519938 1.4986)
			(layers "F.Cu" "F.Mask" "F.Paste")
			(net "M_F_CPU1_SA_PAR")
		)
		(pad "75" smd rect
			(at -2.050034 -0.424942 270)
			(size 0.519938 1.4986)
			(layers "F.Cu" "F.Mask" "F.Paste")
			(net "GND")
		)
		(pad "76" smd rect
			(at -2.050034 5.525008 270)
			(size 0.519938 1.4986)
			(layers "F.Cu" "F.Mask" "F.Paste")
			(net "M_F_CPU1_SB_CA<0>")
		)
		(pad "77" smd rect
			(at -2.050034 6.374892 270)
			(size 0.519938 1.4986)
			(layers "F.Cu" "F.Mask" "F.Paste")
			(net "GND")
		)
		(pad "78" smd rect
			(at -2.050034 7.22503 270)
			(size 0.519938 1.4986)
			(layers "F.Cu" "F.Mask" "F.Paste")
			(net "M_F_CPU1_SB_CA<2>")
		)
		(pad "79" smd rect
			(at -2.050034 8.074914 270)
			(size 0.519938 1.4986)
			(layers "F.Cu" "F.Mask" "F.Paste")
			(net "GND")
		)
		(pad "80" smd rect
			(at -2.050034 8.925052 270)
			(size 0.519938 1.4986)
			(layers "F.Cu" "F.Mask" "F.Paste")
			(net "M_F_CPU1_SB_CA<4>")
		)
		(pad "81" smd rect
			(at -2.050034 9.774936 270)
			(size 0.519938 1.4986)
			(layers "F.Cu" "F.Mask" "F.Paste")
			(net "GND")
		)
		(pad "82" smd rect
			(at -2.050034 10.625074 270)
			(size 0.519938 1.4986)
			(layers "F.Cu" "F.Mask" "F.Paste")
			(net "M_F_CPU1_SB_CA<6>")
		)
		(pad "83" smd rect
			(at -2.050034 11.474958 270)
			(size 0.519938 1.4986)
			(layers "F.Cu" "F.Mask" "F.Paste")
			(net "GND")
		)
		(pad "84" smd rect
			(at -2.050034 12.325096 270)
			(size 0.519938 1.4986)
			(layers "F.Cu" "F.Mask" "F.Paste")
			(net "M_F_CPU1_SB_CS_N<2>")
		)
		(pad "85" smd rect
			(at -2.050034 13.17498 270)
			(size 0.519938 1.4986)
			(layers "F.Cu" "F.Mask" "F.Paste")
			(net "GND")
		)
		(pad "86" smd rect
			(at -2.050034 14.025118 270)
			(size 0.519938 1.4986)
			(layers "F.Cu" "F.Mask" "F.Paste")
			(net "M_F_CPU1_SA_RSP<1>")
		)
		(pad "87" smd rect
			(at -2.050034 14.875002 270)
			(size 0.519938 1.4986)
			(layers "F.Cu" "F.Mask" "F.Paste")
			(net "M_F_CPU1_SB_RSP<1>")
		)
		(pad "88" smd rect
			(at -2.050034 15.724886 270)
			(size 0.519938 1.4986)
			(layers "F.Cu" "F.Mask" "F.Paste")
			(net "GND")
		)
		(pad "89" smd rect
			(at -2.050034 16.575024 270)
			(size 0.519938 1.4986)
			(layers "F.Cu" "F.Mask" "F.Paste")
			(net "M_F_CPU1_SB_CB<4>")
		)
		(pad "90" smd rect
			(at -2.050034 17.424908 270)
			(size 0.519938 1.4986)
			(layers "F.Cu" "F.Mask" "F.Paste")
			(net "GND")
		)
		(pad "91" smd rect
			(at -2.050034 18.275046 270)
			(size 0.519938 1.4986)
			(layers "F.Cu" "F.Mask" "F.Paste")
			(net "M_F_CPU1_SB_CB<5>")
		)
	)
)
